FILE_TYPE = MULTI_PHYS_TABLE;

PART '74LVC2G07DW7'

{========================================================================================}
:VALUE           | PART_TYPE | MATERIAL | PART_NUMBER    = STANDARD    | LIFECYCLE      | PART_NUMBER   | JEDEC_TYPE             | DESCRIPTION                          | MANUFTR | MANUF_PN        | RD_CMPLS_LVL | CMPLS_LVL | FROM_PJ    | CLASS | DIP_SMD | DATA                    | EE_CHECK_LIST | FP_ECN | PSL | CREATOR | STATUS | MSD | ESD_CDM | ESD_HBM | ESD_MM | PIN_LENGTH_SHORT_PIN | PIN_LENGTH_LONG_PIN | CREATEDAY  ;
{========================================================================================}
 '74LVC2G07DW-7' | 'SMLF'    | 'IC'     | 'AL002G07003'(!) = ''               | ''               | 'AL002G07003' |'SOT363_0-65_2X1-25XC'| 'IC OTHER(6P)74LVC2G07DW-7(SOT-363)' | 'DDS'   | '74LVC2G07DW-7' | 'EP(V1)'     | 'EP(V1)'  | 'F0C-IVES' | 'IC'  | ''      | 'DDS_74LVC2G07DW-7.pdf' | ''            | ''     | ''  | ''      | ''     | ''  | ''      | ''      | ''     | '0 MILS'             | '0 MILS'            | '20210611'
 '74LVC2G07DW-7' | 'SMLF'    | 'EMPTY'  | 'AL002G07003'(!) = ''               | ''               | 'AL002G07003' |'SOT363_0-65_2X1-25XC'| 'IC OTHER(6P)74LVC2G07DW-7(SOT-363)' | 'DDS'   | '74LVC2G07DW-7' | 'EP(V1)'     | 'EP(V1)'  | 'F0C-IVES' | 'IC'  | ''      | 'DDS_74LVC2G07DW-7.pdf' | ''            | ''     | ''  | ''      | ''     | ''  | ''      | ''      | ''     | '0 MILS'             | '0 MILS'            | '20210611'

END_PART

END.

